(kicad_pcb
	(version 20260206)
	(generator "pcbnew")
	(generator_version "10.0")
	(general
		(thickness 1.6)
		(legacy_teardrops no)
	)
	(paper "A4")
	(title_block
		(title "04192023_DAF0TMB3IC0_F0TG_MB_C_brd_V02_OCP.brd")
		(comment 1 "Grand Teton / footprints 4667-4671 of 8354")
	)
	(layers
		(0 "F.Cu" signal "TOP")
		(4 "In1.Cu" signal "GND")
		(6 "In2.Cu" signal "IN1")
		(8 "In3.Cu" signal "GND1")
		(10 "In4.Cu" signal "IN2")
		(12 "In5.Cu" signal "GND2")
		(14 "In6.Cu" signal "IN3")
		(16 "In7.Cu" signal "GND3")
		(18 "In8.Cu" signal "VCC")
		(20 "In9.Cu" signal "VCC1")
		(22 "In10.Cu" signal "GND4")
		(24 "In11.Cu" signal "IN4")
		(26 "In12.Cu" signal "GND5")
		(28 "In13.Cu" signal "IN5")
		(30 "In14.Cu" signal "GND6")
		(32 "In15.Cu" signal "IN6")
		(34 "In16.Cu" signal "GND7")
		(2 "B.Cu" signal "BOTTOM")
		(9 "F.Adhes" user "F.Adhesive")
		(11 "B.Adhes" user "B.Adhesive")
		(13 "F.Paste" user "Package Geometry/Pastemask Top")
		(15 "B.Paste" user "Package Geometry/Pastemask Bottom")
		(5 "F.SilkS" user "Ref Des/Silkscreen Top")
		(7 "B.SilkS" user "Ref Des/Silkscreen Bottom")
		(1 "F.Mask" user "Board Geometry/Soldermask Top")
		(3 "B.Mask" user "Board Geometry/Soldermask Bottom")
		(17 "Dwgs.User" user "User.Drawings")
		(19 "Cmts.User" user "User.Comments")
		(21 "Eco1.User" user "User.Eco1")
		(23 "Eco2.User" user "User.Eco2")
		(25 "Edge.Cuts" user "Board Geometry/Outline")
		(27 "Margin" user)
		(31 "F.CrtYd" user "Package Geometry/Place Bound Top")
		(29 "B.CrtYd" user "Package Geometry/Place Bound Bottom")
		(35 "F.Fab" user "Ref Des/Assembly Top")
		(33 "B.Fab" user "Ref Des/Assembly Bottom")
	)
	(footprint ""
		(layer "F.Cu")
		(at 187.28436 -29.77769 -90)
		(property "Reference" "PC2230"
			(at 0 0 270)
			(layer "F.SilkS")
			(hide yes)
			(effects
				(font
					(size 1.27 1.27)
				)
			)
		)
		(property "Value" ""
			(at 0 0 270)
			(layer "F.Fab")
			(effects
				(font
					(size 1.27 1.27)
				)
			)
		)
		(duplicate_pad_numbers_are_jumpers no)
		(fp_line
			(start -0.7874 0.4064)
			(end -0.7874 -0.4064)
			(stroke
				(width 0.1524)
				(type default)
			)
			(layer "F.SilkS")
		)
		(fp_line
			(start 0.7874 0.4064)
			(end -0.7874 0.4064)
			(stroke
				(width 0.1524)
				(type default)
			)
			(layer "F.SilkS")
		)
		(fp_line
			(start -0.7874 -0.4064)
			(end 0.7874 -0.4064)
			(stroke
				(width 0.1524)
				(type default)
			)
			(layer "F.SilkS")
		)
		(fp_line
			(start 0.7874 -0.4064)
			(end 0.7874 0.4064)
			(stroke
				(width 0.1524)
				(type default)
			)
			(layer "F.SilkS")
		)
		(fp_line
			(start -0.67945 0.3048)
			(end -0.67945 -0.305054)
			(stroke
				(width 0.1)
				(type default)
			)
			(layer "F.Fab")
		)
		(fp_line
			(start -0.12065 0.3048)
			(end -0.67945 0.3048)
			(stroke
				(width 0.1)
				(type default)
			)
			(layer "F.Fab")
		)
		(fp_line
			(start 0.120396 0.3048)
			(end 0.120396 0.2794)
			(stroke
				(width 0.1)
				(type default)
			)
			(layer "F.Fab")
		)
		(fp_line
			(start 0.67945 0.3048)
			(end 0.120396 0.3048)
			(stroke
				(width 0.1)
				(type default)
			)
			(layer "F.Fab")
		)
		(fp_line
			(start -0.12065 0.2794)
			(end -0.12065 0.3048)
			(stroke
				(width 0.1)
				(type default)
			)
			(layer "F.Fab")
		)
		(fp_line
			(start 0.120396 0.2794)
			(end -0.12065 0.2794)
			(stroke
				(width 0.1)
				(type default)
			)
			(layer "F.Fab")
		)
		(fp_line
			(start -0.12065 -0.2794)
			(end 0.12065 -0.2794)
			(stroke
				(width 0.1)
				(type default)
			)
			(layer "F.Fab")
		)
		(fp_line
			(start 0.12065 -0.2794)
			(end 0.12065 -0.3048)
			(stroke
				(width 0.1)
				(type default)
			)
			(layer "F.Fab")
		)
		(fp_line
			(start 0.12065 -0.3048)
			(end 0.67945 -0.3048)
			(stroke
				(width 0.1)
				(type default)
			)
			(layer "F.Fab")
		)
		(fp_line
			(start 0.67945 -0.3048)
			(end 0.67945 0.3048)
			(stroke
				(width 0.1)
				(type default)
			)
			(layer "F.Fab")
		)
		(fp_line
			(start -0.67945 -0.305054)
			(end -0.12065 -0.305054)
			(stroke
				(width 0.1)
				(type default)
			)
			(layer "F.Fab")
		)
		(fp_line
			(start -0.12065 -0.305054)
			(end -0.12065 -0.2794)
			(stroke
				(width 0.1)
				(type default)
			)
			(layer "F.Fab")
		)
		(pad "1" smd circle
			(at -0.40005 0 270)
			(size 0 0)
			(layers "F.Cu" "F.Mask" "F.Paste")
			(net "P12V_AUX")
		)
		(pad "2" smd circle
			(at 0.40005 0 270)
			(size 0 0)
			(layers "F.Cu" "F.Mask" "F.Paste")
			(net "GND")
		)
	)
	(footprint ""
		(layer "F.Cu")
		(at 89.809828 -141.42466 90)
		(property "Reference" "R8167"
			(at 0 0 90)
			(layer "F.SilkS")
			(hide yes)
			(effects
				(font
					(size 1.27 1.27)
				)
			)
		)
		(property "Value" ""
			(at 0 0 90)
			(layer "F.Fab")
			(effects
				(font
					(size 1.27 1.27)
				)
			)
		)
		(duplicate_pad_numbers_are_jumpers no)
		(fp_line
			(start 0.7874 -0.4064)
			(end 0.7874 0.4064)
			(stroke
				(width 0.1524)
				(type default)
			)
			(layer "F.SilkS")
		)
		(fp_line
			(start -0.7874 -0.4064)
			(end 0.7874 -0.4064)
			(stroke
				(width 0.1524)
				(type default)
			)
			(layer "F.SilkS")
		)
		(fp_line
			(start 0.7874 0.4064)
			(end -0.7874 0.4064)
			(stroke
				(width 0.1524)
				(type default)
			)
			(layer "F.SilkS")
		)
		(fp_line
			(start -0.7874 0.4064)
			(end -0.7874 -0.4064)
			(stroke
				(width 0.1524)
				(type default)
			)
			(layer "F.SilkS")
		)
		(fp_line
			(start -0.12065 -0.305054)
			(end -0.12065 -0.2794)
			(stroke
				(width 0.1)
				(type default)
			)
			(layer "F.Fab")
		)
		(fp_line
			(start -0.67945 -0.305054)
			(end -0.12065 -0.305054)
			(stroke
				(width 0.1)
				(type default)
			)
			(layer "F.Fab")
		)
		(fp_line
			(start 0.67945 -0.3048)
			(end 0.67945 0.3048)
			(stroke
				(width 0.1)
				(type default)
			)
			(layer "F.Fab")
		)
		(fp_line
			(start 0.12065 -0.3048)
			(end 0.67945 -0.3048)
			(stroke
				(width 0.1)
				(type default)
			)
			(layer "F.Fab")
		)
		(fp_line
			(start 0.12065 -0.2794)
			(end 0.12065 -0.3048)
			(stroke
				(width 0.1)
				(type default)
			)
			(layer "F.Fab")
		)
		(fp_line
			(start -0.12065 -0.2794)
			(end 0.12065 -0.2794)
			(stroke
				(width 0.1)
				(type default)
			)
			(layer "F.Fab")
		)
		(fp_line
			(start 0.120396 0.2794)
			(end -0.12065 0.2794)
			(stroke
				(width 0.1)
				(type default)
			)
			(layer "F.Fab")
		)
		(fp_line
			(start -0.12065 0.2794)
			(end -0.12065 0.3048)
			(stroke
				(width 0.1)
				(type default)
			)
			(layer "F.Fab")
		)
		(fp_line
			(start 0.67945 0.3048)
			(end 0.120396 0.3048)
			(stroke
				(width 0.1)
				(type default)
			)
			(layer "F.Fab")
		)
		(fp_line
			(start 0.120396 0.3048)
			(end 0.120396 0.2794)
			(stroke
				(width 0.1)
				(type default)
			)
			(layer "F.Fab")
		)
		(fp_line
			(start -0.12065 0.3048)
			(end -0.67945 0.3048)
			(stroke
				(width 0.1)
				(type default)
			)
			(layer "F.Fab")
		)
		(fp_line
			(start -0.67945 0.3048)
			(end -0.67945 -0.305054)
			(stroke
				(width 0.1)
				(type default)
			)
			(layer "F.Fab")
		)
		(pad "1" smd circle
			(at -0.40005 0 90)
			(size 0 0)
			(layers "F.Cu" "F.Mask" "F.Paste")
			(net "P3V3_AUX")
		)
		(pad "2" smd circle
			(at 0.40005 0 90)
			(size 0 0)
			(layers "F.Cu" "F.Mask" "F.Paste")
			(net "PWRGD_PVDDCR_CPU0_P1_R")
		)
	)
	(footprint ""
		(layer "F.Cu")
		(at 409.478226 -137.854182)
		(property "Reference" "R6097"
			(at 0 0 0)
			(layer "F.SilkS")
			(hide yes)
			(effects
				(font
					(size 1.27 1.27)
				)
			)
		)
		(property "Value" ""
			(at 0 0 0)
			(layer "F.Fab")
			(effects
				(font
					(size 1.27 1.27)
				)
			)
		)
		(duplicate_pad_numbers_are_jumpers no)
		(fp_line
			(start -0.7874 -0.4064)
			(end 0.7874 -0.4064)
			(stroke
				(width 0.1524)
				(type default)
			)
			(layer "F.SilkS")
		)
		(fp_line
			(start -0.7874 0.4064)
			(end -0.7874 -0.4064)
			(stroke
				(width 0.1524)
				(type default)
			)
			(layer "F.SilkS")
		)
		(fp_line
			(start 0.7874 -0.4064)
			(end 0.7874 0.4064)
			(stroke
				(width 0.1524)
				(type default)
			)
			(layer "F.SilkS")
		)
		(fp_line
			(start 0.7874 0.4064)
			(end -0.7874 0.4064)
			(stroke
				(width 0.1524)
				(type default)
			)
			(layer "F.SilkS")
		)
		(fp_line
			(start -0.67945 -0.305054)
			(end -0.12065 -0.305054)
			(stroke
				(width 0.1)
				(type default)
			)
			(layer "F.Fab")
		)
		(fp_line
			(start -0.67945 0.3048)
			(end -0.67945 -0.305054)
			(stroke
				(width 0.1)
				(type default)
			)
			(layer "F.Fab")
		)
		(fp_line
			(start -0.12065 -0.305054)
			(end -0.12065 -0.2794)
			(stroke
				(width 0.1)
				(type default)
			)
			(layer "F.Fab")
		)
		(fp_line
			(start -0.12065 -0.2794)
			(end 0.12065 -0.2794)
			(stroke
				(width 0.1)
				(type default)
			)
			(layer "F.Fab")
		)
		(fp_line
			(start -0.12065 0.2794)
			(end -0.12065 0.3048)
			(stroke
				(width 0.1)
				(type default)
			)
			(layer "F.Fab")
		)
		(fp_line
			(start -0.12065 0.3048)
			(end -0.67945 0.3048)
			(stroke
				(width 0.1)
				(type default)
			)
			(layer "F.Fab")
		)
		(fp_line
			(start 0.120396 0.2794)
			(end -0.12065 0.2794)
			(stroke
				(width 0.1)
				(type default)
			)
			(layer "F.Fab")
		)
		(fp_line
			(start 0.120396 0.3048)
			(end 0.120396 0.2794)
			(stroke
				(width 0.1)
				(type default)
			)
			(layer "F.Fab")
		)
		(fp_line
			(start 0.12065 -0.3048)
			(end 0.67945 -0.3048)
			(stroke
				(width 0.1)
				(type default)
			)
			(layer "F.Fab")
		)
		(fp_line
			(start 0.12065 -0.2794)
			(end 0.12065 -0.3048)
			(stroke
				(width 0.1)
				(type default)
			)
			(layer "F.Fab")
		)
		(fp_line
			(start 0.67945 -0.3048)
			(end 0.67945 0.3048)
			(stroke
				(width 0.1)
				(type default)
			)
			(layer "F.Fab")
		)
		(fp_line
			(start 0.67945 0.3048)
			(end 0.120396 0.3048)
			(stroke
				(width 0.1)
				(type default)
			)
			(layer "F.Fab")
		)
		(pad "1" smd circle
			(at -0.40005 0)
			(size 0 0)
			(layers "F.Cu" "F.Mask" "F.Paste")
			(net "MB0_P12V_STBY_PWRGD")
		)
		(pad "2" smd circle
			(at 0.40005 0)
			(size 0 0)
			(layers "F.Cu" "F.Mask" "F.Paste")
			(net "P5V_AUX_EN")
		)
	)
	(footprint ""
		(layer "F.Cu")
		(at 266.971526 -97.780856 180)
		(property "Reference" "U149"
			(at 1.889252 -3.344164 0)
			(unlocked yes)
			(layer "F.SilkS")
			(effects
				(font
					(size 0.7874 0.5842)
					(thickness 0.1524)
				)
				(justify left)
			)
		)
		(property "Value" ""
			(at 0 0 180)
			(layer "F.Fab")
			(effects
				(font
					(size 1.27 1.27)
				)
			)
		)
		(duplicate_pad_numbers_are_jumpers no)
		(fp_line
			(start 1.868932 2.549906)
			(end 1.868932 -2.549906)
			(stroke
				(width 0.1524)
				(type default)
			)
			(layer "F.SilkS")
		)
		(fp_line
			(start 1.868932 -2.549906)
			(end 1.025906 -2.549906)
			(stroke
				(width 0.1524)
				(type default)
			)
			(layer "F.SilkS")
		)
		(fp_line
			(start 1.025906 -2.549906)
			(end 0 -1.524)
			(stroke
				(width 0.1524)
				(type default)
			)
			(layer "F.SilkS")
		)
		(fp_line
			(start 0 -1.524)
			(end -1.025906 -2.549906)
			(stroke
				(width 0.1524)
				(type default)
			)
			(layer "F.SilkS")
		)
		(fp_line
			(start -1.025906 -2.549906)
			(end -1.868932 -2.549906)
			(stroke
				(width 0.1524)
				(type default)
			)
			(layer "F.SilkS")
		)
		(fp_line
			(start -1.868932 2.549906)
			(end 1.868932 2.549906)
			(stroke
				(width 0.1524)
				(type default)
			)
			(layer "F.SilkS")
		)
		(fp_line
			(start -1.868932 -2.549906)
			(end -1.868932 2.549906)
			(stroke
				(width 0.1524)
				(type default)
			)
			(layer "F.SilkS")
		)
		(fp_poly
			(pts
				(xy -3.7592 -2.295398) (xy -4.7752 -1.787398) (xy -4.7752 -2.803398)
			)
			(stroke
				(width 0)
				(type default)
			)
			(fill yes)
			(layer "F.SilkS")
		)
		(fp_line
			(start 2.249932 2.549906)
			(end 2.249932 -2.549906)
			(stroke
				(width 0.1)
				(type default)
			)
			(layer "F.Fab")
		)
		(fp_line
			(start 2.249932 -2.549906)
			(end -2.249932 -2.549906)
			(stroke
				(width 0.1)
				(type default)
			)
			(layer "F.Fab")
		)
		(fp_line
			(start -2.249932 2.549906)
			(end 2.249932 2.549906)
			(stroke
				(width 0.1)
				(type default)
			)
			(layer "F.Fab")
		)
		(fp_line
			(start -2.249932 -2.549906)
			(end -2.249932 2.549906)
			(stroke
				(width 0.1)
				(type default)
			)
			(layer "F.Fab")
		)
		(fp_poly
			(pts
				(xy -4.7752 -1.787398) (xy -4.7752 -2.803398) (xy -3.7592 -2.295398)
			)
			(stroke
				(width 0)
				(type default)
			)
			(fill yes)
			(layer "F.Fab")
		)
		(pad "1" smd rect
			(at -2.800096 -2.275078 90)
			(size 0.3556 1.6002)
			(layers "F.Cu" "F.Mask" "F.Paste")
			(net "PVDD18_S5_P0")
		)
		(pad "2" smd rect
			(at -2.800096 -1.625092 90)
			(size 0.3556 1.6002)
			(layers "F.Cu" "F.Mask" "F.Paste")
			(net "PVDD18_S5_P0")
		)
		(pad "3" smd rect
			(at -2.800096 -0.975106 90)
			(size 0.3556 1.6002)
			(layers "F.Cu" "F.Mask" "F.Paste")
			(net "HDT_HDR_TCK")
		)
		(pad "4" smd rect
			(at -2.800096 -0.32512 90)
			(size 0.3556 1.6002)
			(layers "F.Cu" "F.Mask" "F.Paste")
			(net "HDT_HDR_TMS")
		)
		(pad "5" smd rect
			(at -2.800096 0.32512 90)
			(size 0.3556 1.6002)
			(layers "F.Cu" "F.Mask" "F.Paste")
			(net "HDT_HDR_TRST_N")
		)
		(pad "6" smd rect
			(at -2.800096 0.975106 90)
			(size 0.3556 1.6002)
			(layers "F.Cu" "F.Mask" "F.Paste")
			(net "HDT_HDR_DBREQ_N")
		)
		(pad "7" smd rect
			(at -2.800096 1.625092 90)
			(size 0.3556 1.6002)
			(layers "F.Cu" "F.Mask" "F.Paste")
			(net "PVDD18_S5_P0")
		)
		(pad "8" smd rect
			(at -2.800096 2.275078 90)
			(size 0.3556 1.6002)
			(layers "F.Cu" "F.Mask" "F.Paste")
			(net "PVDD18_S5_P0")
		)
		(pad "9" smd rect
			(at 2.800096 2.275078 90)
			(size 0.3556 1.6002)
			(layers "F.Cu" "F.Mask" "F.Paste")
			(net "JTAG_BMC_R_D_OE")
		)
		(pad "10" smd rect
			(at 2.800096 1.625092 90)
			(size 0.3556 1.6002)
			(layers "F.Cu" "F.Mask" "F.Paste")
			(net "GND")
		)
		(pad "11" smd rect
			(at 2.800096 0.975106 90)
			(size 0.3556 1.6002)
			(layers "F.Cu" "F.Mask" "F.Paste")
			(net "JTAG_DBREQ_R_N")
		)
		(pad "12" smd rect
			(at 2.800096 0.32512 90)
			(size 0.3556 1.6002)
			(layers "F.Cu" "F.Mask" "F.Paste")
			(net "JTAG_TRST_R_N")
		)
		(pad "13" smd rect
			(at 2.800096 -0.32512 90)
			(size 0.3556 1.6002)
			(layers "F.Cu" "F.Mask" "F.Paste")
			(net "JTAG_TMS_R")
		)
		(pad "14" smd rect
			(at 2.800096 -0.975106 90)
			(size 0.3556 1.6002)
			(layers "F.Cu" "F.Mask" "F.Paste")
			(net "JTAG_TCK_R")
		)
		(pad "15" smd rect
			(at 2.800096 -1.625092 90)
			(size 0.3556 1.6002)
			(layers "F.Cu" "F.Mask" "F.Paste")
			(net "PVDD18_S5_P0")
		)
		(pad "16" smd rect
			(at 2.800096 -2.275078 90)
			(size 0.3556 1.6002)
			(layers "F.Cu" "F.Mask" "F.Paste")
			(net "PVDD18_S5_P0")
		)
	)
	(footprint ""
		(layer "F.Cu")
		(at 401.51812 -180.175408)
		(property "Reference" "PC185"
			(at 0 0 0)
			(layer "F.SilkS")
			(hide yes)
			(effects
				(font
					(size 1.27 1.27)
				)
			)
		)
		(property "Value" ""
			(at 0 0 0)
			(layer "F.Fab")
			(effects
				(font
					(size 1.27 1.27)
				)
			)
		)
		(duplicate_pad_numbers_are_jumpers no)
		(fp_line
			(start -0.7874 -0.4064)
			(end 0.7874 -0.4064)
			(stroke
				(width 0.1524)
				(type default)
			)
			(layer "F.SilkS")
		)
		(fp_line
			(start -0.7874 0.4064)
			(end -0.7874 -0.4064)
			(stroke
				(width 0.1524)
				(type default)
			)
			(layer "F.SilkS")
		)
		(fp_line
			(start 0.7874 -0.4064)
			(end 0.7874 0.4064)
			(stroke
				(width 0.1524)
				(type default)
			)
			(layer "F.SilkS")
		)
		(fp_line
			(start 0.7874 0.4064)
			(end -0.7874 0.4064)
			(stroke
				(width 0.1524)
				(type default)
			)
			(layer "F.SilkS")
		)
		(fp_line
			(start -0.67945 -0.305054)
			(end -0.12065 -0.305054)
			(stroke
				(width 0.1)
				(type default)
			)
			(layer "F.Fab")
		)
		(fp_line
			(start -0.67945 0.3048)
			(end -0.67945 -0.305054)
			(stroke
				(width 0.1)
				(type default)
			)
			(layer "F.Fab")
		)
		(fp_line
			(start -0.12065 -0.305054)
			(end -0.12065 -0.2794)
			(stroke
				(width 0.1)
				(type default)
			)
			(layer "F.Fab")
		)
		(fp_line
			(start -0.12065 -0.2794)
			(end 0.12065 -0.2794)
			(stroke
				(width 0.1)
				(type default)
			)
			(layer "F.Fab")
		)
		(fp_line
			(start -0.12065 0.2794)
			(end -0.12065 0.3048)
			(stroke
				(width 0.1)
				(type default)
			)
			(layer "F.Fab")
		)
		(fp_line
			(start -0.12065 0.3048)
			(end -0.67945 0.3048)
			(stroke
				(width 0.1)
				(type default)
			)
			(layer "F.Fab")
		)
		(fp_line
			(start 0.120396 0.2794)
			(end -0.12065 0.2794)
			(stroke
				(width 0.1)
				(type default)
			)
			(layer "F.Fab")
		)
		(fp_line
			(start 0.120396 0.3048)
			(end 0.120396 0.2794)
			(stroke
				(width 0.1)
				(type default)
			)
			(layer "F.Fab")
		)
		(fp_line
			(start 0.12065 -0.3048)
			(end 0.67945 -0.3048)
			(stroke
				(width 0.1)
				(type default)
			)
			(layer "F.Fab")
		)
		(fp_line
			(start 0.12065 -0.2794)
			(end 0.12065 -0.3048)
			(stroke
				(width 0.1)
				(type default)
			)
			(layer "F.Fab")
		)
		(fp_line
			(start 0.67945 -0.3048)
			(end 0.67945 0.3048)
			(stroke
				(width 0.1)
				(type default)
			)
			(layer "F.Fab")
		)
		(fp_line
			(start 0.67945 0.3048)
			(end 0.120396 0.3048)
			(stroke
				(width 0.1)
				(type default)
			)
			(layer "F.Fab")
		)
		(pad "1" smd circle
			(at -0.40005 0)
			(size 0 0)
			(layers "F.Cu" "F.Mask" "F.Paste")
			(net "SW_PVDDCR_SOC_P0_SW1")
		)
		(pad "2" smd circle
			(at 0.40005 0)
			(size 0 0)
			(layers "F.Cu" "F.Mask" "F.Paste")
			(net "SW_PVDDCR_SOC_P0_SW1_RC")
		)
	)
)
